(kicad_pcb
	(version 20260206)
	(generator "pcbnew")
	(generator_version "10.0")
	(general
		(thickness 1.6)
		(legacy_teardrops no)
	)
	(paper "A4")
	(title_block
		(title "12092022_DA0F0TMDCD0_F0T_Management_Board_D_brd_V3_OCP.brd")
		(comment 1 "Grand Teton / footprints 1374-1379 of 1440")
	)
	(layers
		(0 "F.Cu" signal "TOP")
		(4 "In1.Cu" signal "GND")
		(6 "In2.Cu" signal "IN1")
		(8 "In3.Cu" signal "GND1")
		(10 "In4.Cu" signal "IN2")
		(12 "In5.Cu" signal "VCC")
		(14 "In6.Cu" signal "VCC1")
		(16 "In7.Cu" signal "IN3")
		(18 "In8.Cu" signal "GND2")
		(20 "In9.Cu" signal "IN4")
		(22 "In10.Cu" signal "GND3")
		(2 "B.Cu" signal "BOTTOM")
		(9 "F.Adhes" user "F.Adhesive")
		(11 "B.Adhes" user "B.Adhesive")
		(13 "F.Paste" user "Package Geometry/Pastemask Top")
		(15 "B.Paste" user "Package Geometry/Pastemask Bottom")
		(5 "F.SilkS" user "Ref Des/Silkscreen Top")
		(7 "B.SilkS" user "Ref Des/Silkscreen Bottom")
		(1 "F.Mask" user "Board Geometry/Soldermask Top")
		(3 "B.Mask" user "Board Geometry/Soldermask Bottom")
		(17 "Dwgs.User" user "User.Drawings")
		(19 "Cmts.User" user "User.Comments")
		(21 "Eco1.User" user "User.Eco1")
		(23 "Eco2.User" user "User.Eco2")
		(25 "Edge.Cuts" user "Board Geometry/Outline")
		(27 "Margin" user)
		(31 "F.CrtYd" user "Package Geometry/Place Bound Top")
		(29 "B.CrtYd" user "Package Geometry/Place Bound Bottom")
		(35 "F.Fab" user "Ref Des/Assembly Top")
		(33 "B.Fab" user "Ref Des/Assembly Bottom")
	)
	(footprint ""
		(layer "B.Cu")
		(at 29.4894 -93.1164)
		(property "Reference" "R773"
			(at 0 0 0)
			(layer "B.SilkS")
			(hide yes)
			(effects
				(font
					(size 1.27 1.27)
				)
				(justify mirror)
			)
		)
		(property "Value" ""
			(at 0 0 0)
			(layer "B.Fab")
			(effects
				(font
					(size 1.27 1.27)
				)
				(justify mirror)
			)
		)
		(duplicate_pad_numbers_are_jumpers no)
		(fp_line
			(start -0.7874 -0.4064)
			(end -0.7874 0.4064)
			(stroke
				(width 0.1524)
				(type default)
			)
			(layer "B.SilkS")
		)
		(fp_line
			(start -0.7874 0.4064)
			(end 0.7874 0.4064)
			(stroke
				(width 0.1524)
				(type default)
			)
			(layer "B.SilkS")
		)
		(fp_line
			(start 0.7874 -0.4064)
			(end -0.7874 -0.4064)
			(stroke
				(width 0.1524)
				(type default)
			)
			(layer "B.SilkS")
		)
		(fp_line
			(start 0.7874 0.4064)
			(end 0.7874 -0.4064)
			(stroke
				(width 0.1524)
				(type default)
			)
			(layer "B.SilkS")
		)
		(fp_line
			(start -0.67945 -0.3048)
			(end -0.67945 0.3048)
			(stroke
				(width 0.1)
				(type default)
			)
			(layer "B.Fab")
		)
		(fp_line
			(start -0.67945 0.3048)
			(end -0.120396 0.3048)
			(stroke
				(width 0.1)
				(type default)
			)
			(layer "B.Fab")
		)
		(fp_line
			(start -0.12065 -0.3048)
			(end -0.67945 -0.3048)
			(stroke
				(width 0.1)
				(type default)
			)
			(layer "B.Fab")
		)
		(fp_line
			(start -0.12065 -0.2794)
			(end -0.12065 -0.3048)
			(stroke
				(width 0.1)
				(type default)
			)
			(layer "B.Fab")
		)
		(fp_line
			(start -0.120396 0.2794)
			(end 0.12065 0.2794)
			(stroke
				(width 0.1)
				(type default)
			)
			(layer "B.Fab")
		)
		(fp_line
			(start -0.120396 0.3048)
			(end -0.120396 0.2794)
			(stroke
				(width 0.1)
				(type default)
			)
			(layer "B.Fab")
		)
		(fp_line
			(start 0.12065 -0.305054)
			(end 0.12065 -0.2794)
			(stroke
				(width 0.1)
				(type default)
			)
			(layer "B.Fab")
		)
		(fp_line
			(start 0.12065 -0.2794)
			(end -0.12065 -0.2794)
			(stroke
				(width 0.1)
				(type default)
			)
			(layer "B.Fab")
		)
		(fp_line
			(start 0.12065 0.2794)
			(end 0.12065 0.3048)
			(stroke
				(width 0.1)
				(type default)
			)
			(layer "B.Fab")
		)
		(fp_line
			(start 0.12065 0.3048)
			(end 0.67945 0.3048)
			(stroke
				(width 0.1)
				(type default)
			)
			(layer "B.Fab")
		)
		(fp_line
			(start 0.67945 -0.305054)
			(end 0.12065 -0.305054)
			(stroke
				(width 0.1)
				(type default)
			)
			(layer "B.Fab")
		)
		(fp_line
			(start 0.67945 0.3048)
			(end 0.67945 -0.305054)
			(stroke
				(width 0.1)
				(type default)
			)
			(layer "B.Fab")
		)
		(pad "1" smd circle
			(at 0.40005 0 180)
			(size 0 0)
			(layers "B.Cu" "B.Mask" "B.Paste")
			(net "FM_SLPS3_GF_N")
		)
		(pad "2" smd circle
			(at -0.40005 0 180)
			(size 0 0)
			(layers "B.Cu" "B.Mask" "B.Paste")
			(net "FM_SLPS3_GF_R_N")
		)
	)
	(footprint ""
		(layer "B.Cu")
		(at 12.319 -87.376 180)
		(property "Reference" "R456"
			(at 0 0 0)
			(layer "B.SilkS")
			(hide yes)
			(effects
				(font
					(size 1.27 1.27)
				)
				(justify mirror)
			)
		)
		(property "Value" ""
			(at 0 0 0)
			(layer "B.Fab")
			(effects
				(font
					(size 1.27 1.27)
				)
				(justify mirror)
			)
		)
		(duplicate_pad_numbers_are_jumpers no)
		(fp_line
			(start 0.7874 0.4064)
			(end 0.7874 -0.4064)
			(stroke
				(width 0.1524)
				(type default)
			)
			(layer "B.SilkS")
		)
		(fp_line
			(start 0.7874 -0.4064)
			(end -0.7874 -0.4064)
			(stroke
				(width 0.1524)
				(type default)
			)
			(layer "B.SilkS")
		)
		(fp_line
			(start -0.7874 0.4064)
			(end 0.7874 0.4064)
			(stroke
				(width 0.1524)
				(type default)
			)
			(layer "B.SilkS")
		)
		(fp_line
			(start -0.7874 -0.4064)
			(end -0.7874 0.4064)
			(stroke
				(width 0.1524)
				(type default)
			)
			(layer "B.SilkS")
		)
		(fp_line
			(start 0.67945 0.3048)
			(end 0.67945 -0.305054)
			(stroke
				(width 0.1)
				(type default)
			)
			(layer "B.Fab")
		)
		(fp_line
			(start 0.67945 -0.305054)
			(end 0.12065 -0.305054)
			(stroke
				(width 0.1)
				(type default)
			)
			(layer "B.Fab")
		)
		(fp_line
			(start 0.12065 0.3048)
			(end 0.67945 0.3048)
			(stroke
				(width 0.1)
				(type default)
			)
			(layer "B.Fab")
		)
		(fp_line
			(start 0.12065 0.2794)
			(end 0.12065 0.3048)
			(stroke
				(width 0.1)
				(type default)
			)
			(layer "B.Fab")
		)
		(fp_line
			(start 0.12065 -0.2794)
			(end -0.12065 -0.2794)
			(stroke
				(width 0.1)
				(type default)
			)
			(layer "B.Fab")
		)
		(fp_line
			(start 0.12065 -0.305054)
			(end 0.12065 -0.2794)
			(stroke
				(width 0.1)
				(type default)
			)
			(layer "B.Fab")
		)
		(fp_line
			(start -0.120396 0.3048)
			(end -0.120396 0.2794)
			(stroke
				(width 0.1)
				(type default)
			)
			(layer "B.Fab")
		)
		(fp_line
			(start -0.120396 0.2794)
			(end 0.12065 0.2794)
			(stroke
				(width 0.1)
				(type default)
			)
			(layer "B.Fab")
		)
		(fp_line
			(start -0.12065 -0.2794)
			(end -0.12065 -0.3048)
			(stroke
				(width 0.1)
				(type default)
			)
			(layer "B.Fab")
		)
		(fp_line
			(start -0.12065 -0.3048)
			(end -0.67945 -0.3048)
			(stroke
				(width 0.1)
				(type default)
			)
			(layer "B.Fab")
		)
		(fp_line
			(start -0.67945 0.3048)
			(end -0.120396 0.3048)
			(stroke
				(width 0.1)
				(type default)
			)
			(layer "B.Fab")
		)
		(fp_line
			(start -0.67945 -0.3048)
			(end -0.67945 0.3048)
			(stroke
				(width 0.1)
				(type default)
			)
			(layer "B.Fab")
		)
		(pad "1" smd circle
			(at 0.40005 0)
			(size 0 0)
			(layers "B.Cu" "B.Mask" "B.Paste")
			(net "SMB_BMC_ALERT9_N")
		)
		(pad "2" smd circle
			(at -0.40005 0)
			(size 0 0)
			(layers "B.Cu" "B.Mask" "B.Paste")
			(net "SMB_BMC_ALERT9_R1_N")
		)
	)
	(footprint ""
		(layer "B.Cu")
		(at 75.528678 -59.618118 90)
		(property "Reference" "C90"
			(at 0 0 90)
			(layer "B.SilkS")
			(hide yes)
			(effects
				(font
					(size 1.27 1.27)
				)
				(justify mirror)
			)
		)
		(property "Value" ""
			(at 0 0 90)
			(layer "B.Fab")
			(effects
				(font
					(size 1.27 1.27)
				)
				(justify mirror)
			)
		)
		(duplicate_pad_numbers_are_jumpers no)
		(fp_line
			(start 0.7874 -0.4064)
			(end -0.7874 -0.4064)
			(stroke
				(width 0.1524)
				(type default)
			)
			(layer "B.SilkS")
		)
		(fp_line
			(start -0.7874 -0.4064)
			(end -0.7874 0.4064)
			(stroke
				(width 0.1524)
				(type default)
			)
			(layer "B.SilkS")
		)
		(fp_line
			(start 0.7874 0.4064)
			(end 0.7874 -0.4064)
			(stroke
				(width 0.1524)
				(type default)
			)
			(layer "B.SilkS")
		)
		(fp_line
			(start -0.7874 0.4064)
			(end 0.7874 0.4064)
			(stroke
				(width 0.1524)
				(type default)
			)
			(layer "B.SilkS")
		)
		(fp_line
			(start 0.67945 -0.305054)
			(end 0.12065 -0.305054)
			(stroke
				(width 0.1)
				(type default)
			)
			(layer "B.Fab")
		)
		(fp_line
			(start 0.12065 -0.305054)
			(end 0.12065 -0.2794)
			(stroke
				(width 0.1)
				(type default)
			)
			(layer "B.Fab")
		)
		(fp_line
			(start -0.12065 -0.3048)
			(end -0.67945 -0.3048)
			(stroke
				(width 0.1)
				(type default)
			)
			(layer "B.Fab")
		)
		(fp_line
			(start -0.67945 -0.3048)
			(end -0.67945 0.3048)
			(stroke
				(width 0.1)
				(type default)
			)
			(layer "B.Fab")
		)
		(fp_line
			(start 0.12065 -0.2794)
			(end -0.12065 -0.2794)
			(stroke
				(width 0.1)
				(type default)
			)
			(layer "B.Fab")
		)
		(fp_line
			(start -0.12065 -0.2794)
			(end -0.12065 -0.3048)
			(stroke
				(width 0.1)
				(type default)
			)
			(layer "B.Fab")
		)
		(fp_line
			(start 0.12065 0.2794)
			(end 0.12065 0.3048)
			(stroke
				(width 0.1)
				(type default)
			)
			(layer "B.Fab")
		)
		(fp_line
			(start -0.120396 0.2794)
			(end 0.12065 0.2794)
			(stroke
				(width 0.1)
				(type default)
			)
			(layer "B.Fab")
		)
		(fp_line
			(start 0.67945 0.3048)
			(end 0.67945 -0.305054)
			(stroke
				(width 0.1)
				(type default)
			)
			(layer "B.Fab")
		)
		(fp_line
			(start 0.12065 0.3048)
			(end 0.67945 0.3048)
			(stroke
				(width 0.1)
				(type default)
			)
			(layer "B.Fab")
		)
		(fp_line
			(start -0.120396 0.3048)
			(end -0.120396 0.2794)
			(stroke
				(width 0.1)
				(type default)
			)
			(layer "B.Fab")
		)
		(fp_line
			(start -0.67945 0.3048)
			(end -0.120396 0.3048)
			(stroke
				(width 0.1)
				(type default)
			)
			(layer "B.Fab")
		)
		(pad "1" smd circle
			(at 0.40005 0 270)
			(size 0 0)
			(layers "B.Cu" "B.Mask" "B.Paste")
			(net "P1V0_STBY_DP_VCC10A")
		)
		(pad "2" smd circle
			(at -0.40005 0 270)
			(size 0 0)
			(layers "B.Cu" "B.Mask" "B.Paste")
			(net "GND")
		)
	)
	(footprint ""
		(layer "B.Cu")
		(at 85.281262 -43.411394 180)
		(property "Reference" "R360"
			(at 0 0 0)
			(layer "B.SilkS")
			(hide yes)
			(effects
				(font
					(size 1.27 1.27)
				)
				(justify mirror)
			)
		)
		(property "Value" ""
			(at 0 0 0)
			(layer "B.Fab")
			(effects
				(font
					(size 1.27 1.27)
				)
				(justify mirror)
			)
		)
		(duplicate_pad_numbers_are_jumpers no)
		(fp_line
			(start 0.7874 0.4064)
			(end 0.7874 -0.4064)
			(stroke
				(width 0.1524)
				(type default)
			)
			(layer "B.SilkS")
		)
		(fp_line
			(start 0.7874 -0.4064)
			(end -0.7874 -0.4064)
			(stroke
				(width 0.1524)
				(type default)
			)
			(layer "B.SilkS")
		)
		(fp_line
			(start -0.7874 0.4064)
			(end 0.7874 0.4064)
			(stroke
				(width 0.1524)
				(type default)
			)
			(layer "B.SilkS")
		)
		(fp_line
			(start -0.7874 -0.4064)
			(end -0.7874 0.4064)
			(stroke
				(width 0.1524)
				(type default)
			)
			(layer "B.SilkS")
		)
		(fp_line
			(start 0.67945 0.3048)
			(end 0.67945 -0.305054)
			(stroke
				(width 0.1)
				(type default)
			)
			(layer "B.Fab")
		)
		(fp_line
			(start 0.67945 -0.305054)
			(end 0.12065 -0.305054)
			(stroke
				(width 0.1)
				(type default)
			)
			(layer "B.Fab")
		)
		(fp_line
			(start 0.12065 0.3048)
			(end 0.67945 0.3048)
			(stroke
				(width 0.1)
				(type default)
			)
			(layer "B.Fab")
		)
		(fp_line
			(start 0.12065 0.2794)
			(end 0.12065 0.3048)
			(stroke
				(width 0.1)
				(type default)
			)
			(layer "B.Fab")
		)
		(fp_line
			(start 0.12065 -0.2794)
			(end -0.12065 -0.2794)
			(stroke
				(width 0.1)
				(type default)
			)
			(layer "B.Fab")
		)
		(fp_line
			(start 0.12065 -0.305054)
			(end 0.12065 -0.2794)
			(stroke
				(width 0.1)
				(type default)
			)
			(layer "B.Fab")
		)
		(fp_line
			(start -0.120396 0.3048)
			(end -0.120396 0.2794)
			(stroke
				(width 0.1)
				(type default)
			)
			(layer "B.Fab")
		)
		(fp_line
			(start -0.120396 0.2794)
			(end 0.12065 0.2794)
			(stroke
				(width 0.1)
				(type default)
			)
			(layer "B.Fab")
		)
		(fp_line
			(start -0.12065 -0.2794)
			(end -0.12065 -0.3048)
			(stroke
				(width 0.1)
				(type default)
			)
			(layer "B.Fab")
		)
		(fp_line
			(start -0.12065 -0.3048)
			(end -0.67945 -0.3048)
			(stroke
				(width 0.1)
				(type default)
			)
			(layer "B.Fab")
		)
		(fp_line
			(start -0.67945 0.3048)
			(end -0.120396 0.3048)
			(stroke
				(width 0.1)
				(type default)
			)
			(layer "B.Fab")
		)
		(fp_line
			(start -0.67945 -0.3048)
			(end -0.67945 0.3048)
			(stroke
				(width 0.1)
				(type default)
			)
			(layer "B.Fab")
		)
		(pad "1" smd circle
			(at 0.40005 0)
			(size 0 0)
			(layers "B.Cu" "B.Mask" "B.Paste")
			(net "M_BMC_DDR4_MA<9>")
		)
		(pad "2" smd circle
			(at -0.40005 0)
			(size 0 0)
			(layers "B.Cu" "B.Mask" "B.Paste")
			(net "P1V2_AUX")
		)
	)
	(footprint ""
		(layer "B.Cu")
		(at 64.634364 -62.037722 -90)
		(property "Reference" "R128"
			(at 0 0 90)
			(layer "B.SilkS")
			(hide yes)
			(effects
				(font
					(size 1.27 1.27)
				)
				(justify mirror)
			)
		)
		(property "Value" ""
			(at 0 0 90)
			(layer "B.Fab")
			(effects
				(font
					(size 1.27 1.27)
				)
				(justify mirror)
			)
		)
		(duplicate_pad_numbers_are_jumpers no)
		(fp_line
			(start -0.7874 0.4064)
			(end 0.7874 0.4064)
			(stroke
				(width 0.1524)
				(type default)
			)
			(layer "B.SilkS")
		)
		(fp_line
			(start 0.7874 0.4064)
			(end 0.7874 -0.4064)
			(stroke
				(width 0.1524)
				(type default)
			)
			(layer "B.SilkS")
		)
		(fp_line
			(start -0.7874 -0.4064)
			(end -0.7874 0.4064)
			(stroke
				(width 0.1524)
				(type default)
			)
			(layer "B.SilkS")
		)
		(fp_line
			(start 0.7874 -0.4064)
			(end -0.7874 -0.4064)
			(stroke
				(width 0.1524)
				(type default)
			)
			(layer "B.SilkS")
		)
		(fp_line
			(start -0.67945 0.3048)
			(end -0.120396 0.3048)
			(stroke
				(width 0.1)
				(type default)
			)
			(layer "B.Fab")
		)
		(fp_line
			(start -0.120396 0.3048)
			(end -0.120396 0.2794)
			(stroke
				(width 0.1)
				(type default)
			)
			(layer "B.Fab")
		)
		(fp_line
			(start 0.12065 0.3048)
			(end 0.67945 0.3048)
			(stroke
				(width 0.1)
				(type default)
			)
			(layer "B.Fab")
		)
		(fp_line
			(start 0.67945 0.3048)
			(end 0.67945 -0.305054)
			(stroke
				(width 0.1)
				(type default)
			)
			(layer "B.Fab")
		)
		(fp_line
			(start -0.120396 0.2794)
			(end 0.12065 0.2794)
			(stroke
				(width 0.1)
				(type default)
			)
			(layer "B.Fab")
		)
		(fp_line
			(start 0.12065 0.2794)
			(end 0.12065 0.3048)
			(stroke
				(width 0.1)
				(type default)
			)
			(layer "B.Fab")
		)
		(fp_line
			(start -0.12065 -0.2794)
			(end -0.12065 -0.3048)
			(stroke
				(width 0.1)
				(type default)
			)
			(layer "B.Fab")
		)
		(fp_line
			(start 0.12065 -0.2794)
			(end -0.12065 -0.2794)
			(stroke
				(width 0.1)
				(type default)
			)
			(layer "B.Fab")
		)
		(fp_line
			(start -0.67945 -0.3048)
			(end -0.67945 0.3048)
			(stroke
				(width 0.1)
				(type default)
			)
			(layer "B.Fab")
		)
		(fp_line
			(start -0.12065 -0.3048)
			(end -0.67945 -0.3048)
			(stroke
				(width 0.1)
				(type default)
			)
			(layer "B.Fab")
		)
		(fp_line
			(start 0.12065 -0.305054)
			(end 0.12065 -0.2794)
			(stroke
				(width 0.1)
				(type default)
			)
			(layer "B.Fab")
		)
		(fp_line
			(start 0.67945 -0.305054)
			(end 0.12065 -0.305054)
			(stroke
				(width 0.1)
				(type default)
			)
			(layer "B.Fab")
		)
		(pad "1" smd circle
			(at 0.40005 0 90)
			(size 0 0)
			(layers "B.Cu" "B.Mask" "B.Paste")
			(net "ESPI_LPC_D0_IO0")
		)
		(pad "2" smd circle
			(at -0.40005 0 90)
			(size 0 0)
			(layers "B.Cu" "B.Mask" "B.Paste")
			(net "ESPI_LPC_LAD0_IO0")
		)
	)
	(footprint ""
		(layer "B.Cu")
		(at 50.905156 -60.26277 180)
		(property "Reference" "C137"
			(at 0 0 0)
			(layer "B.SilkS")
			(hide yes)
			(effects
				(font
					(size 1.27 1.27)
				)
				(justify mirror)
			)
		)
		(property "Value" ""
			(at 0 0 0)
			(layer "B.Fab")
			(effects
				(font
					(size 1.27 1.27)
				)
				(justify mirror)
			)
		)
		(duplicate_pad_numbers_are_jumpers no)
		(fp_line
			(start 0.7874 0.4064)
			(end 0.7874 -0.4064)
			(stroke
				(width 0.1524)
				(type default)
			)
			(layer "B.SilkS")
		)
		(fp_line
			(start 0.7874 -0.4064)
			(end -0.7874 -0.4064)
			(stroke
				(width 0.1524)
				(type default)
			)
			(layer "B.SilkS")
		)
		(fp_line
			(start -0.7874 0.4064)
			(end 0.7874 0.4064)
			(stroke
				(width 0.1524)
				(type default)
			)
			(layer "B.SilkS")
		)
		(fp_line
			(start -0.7874 -0.4064)
			(end -0.7874 0.4064)
			(stroke
				(width 0.1524)
				(type default)
			)
			(layer "B.SilkS")
		)
		(fp_line
			(start 0.67945 0.3048)
			(end 0.67945 -0.305054)
			(stroke
				(width 0.1)
				(type default)
			)
			(layer "B.Fab")
		)
		(fp_line
			(start 0.67945 -0.305054)
			(end 0.12065 -0.305054)
			(stroke
				(width 0.1)
				(type default)
			)
			(layer "B.Fab")
		)
		(fp_line
			(start 0.12065 0.3048)
			(end 0.67945 0.3048)
			(stroke
				(width 0.1)
				(type default)
			)
			(layer "B.Fab")
		)
		(fp_line
			(start 0.12065 0.2794)
			(end 0.12065 0.3048)
			(stroke
				(width 0.1)
				(type default)
			)
			(layer "B.Fab")
		)
		(fp_line
			(start 0.12065 -0.2794)
			(end -0.12065 -0.2794)
			(stroke
				(width 0.1)
				(type default)
			)
			(layer "B.Fab")
		)
		(fp_line
			(start 0.12065 -0.305054)
			(end 0.12065 -0.2794)
			(stroke
				(width 0.1)
				(type default)
			)
			(layer "B.Fab")
		)
		(fp_line
			(start -0.120396 0.3048)
			(end -0.120396 0.2794)
			(stroke
				(width 0.1)
				(type default)
			)
			(layer "B.Fab")
		)
		(fp_line
			(start -0.120396 0.2794)
			(end 0.12065 0.2794)
			(stroke
				(width 0.1)
				(type default)
			)
			(layer "B.Fab")
		)
		(fp_line
			(start -0.12065 -0.2794)
			(end -0.12065 -0.3048)
			(stroke
				(width 0.1)
				(type default)
			)
			(layer "B.Fab")
		)
		(fp_line
			(start -0.12065 -0.3048)
			(end -0.67945 -0.3048)
			(stroke
				(width 0.1)
				(type default)
			)
			(layer "B.Fab")
		)
		(fp_line
			(start -0.67945 0.3048)
			(end -0.120396 0.3048)
			(stroke
				(width 0.1)
				(type default)
			)
			(layer "B.Fab")
		)
		(fp_line
			(start -0.67945 -0.3048)
			(end -0.67945 0.3048)
			(stroke
				(width 0.1)
				(type default)
			)
			(layer "B.Fab")
		)
		(pad "1" smd circle
			(at 0.40005 0)
			(size 0 0)
			(layers "B.Cu" "B.Mask" "B.Paste")
			(net "A_BMC_ADCVREFN1")
		)
		(pad "2" smd circle
			(at -0.40005 0)
			(size 0 0)
			(layers "B.Cu" "B.Mask" "B.Paste")
			(net "A_BMC_ADCVREFP1")
		)
	)
)
